# T6G (Grand Teton) — schematic netlist excerpt (pin names and nets, part order shuffled) for the footprints in the layout excerpt that follows; sources: Cadence DE-HDL packaged netlist, KiCad conversion of 04192023_DAF0TMB3IC0_F0TG_MB_C_brd_V02_OCP.brd

R6746  Q_RES  0 5% CHIP  pkg 0201LF  page 184 : A = SMB_RT_CPU1_P3_R_SDA ; B = SMB_RT_CPU1_P3_SDA
PC514_2  Q_CAP  22UF 16V 20% X6S  pkg C0805  page 225 : A = SW_P12V_AUX_PVDD11_S3_P1_FLT ; B = GND
R6763  Q_RES  1K 1% CHIP  pkg 0201LF  page 184 : A = P1V8_CPU0_RT_1D ; B = SMB_RT_CPU0_P0_R_SCL
C976  Q_CAP  4.7UF 6.3V 20% X6S  pkg 0402  page 301 : A = P0V9_CPU0_RT_2D ; B = GND

(kicad_pcb
	(version 20260206)
	(generator "pcbnew")
	(generator_version "10.0")
	(general
		(thickness 1.6)
		(legacy_teardrops no)
	)
	(paper "A4")
	(title_block
		(title "04192023_DAF0TMB3IC0_F0TG_MB_C_brd_V02_OCP.brd")
		(comment 1 "Grand Teton / footprints 7980-7983 of 8354")
	)
	(layers
		(0 "F.Cu" signal "TOP")
		(4 "In1.Cu" signal "GND")
		(6 "In2.Cu" signal "IN1")
		(8 "In3.Cu" signal "GND1")
		(10 "In4.Cu" signal "IN2")
		(12 "In5.Cu" signal "GND2")
		(14 "In6.Cu" signal "IN3")
		(16 "In7.Cu" signal "GND3")
		(18 "In8.Cu" signal "VCC")
		(20 "In9.Cu" signal "VCC1")
		(22 "In10.Cu" signal "GND4")
		(24 "In11.Cu" signal "IN4")
		(26 "In12.Cu" signal "GND5")
		(28 "In13.Cu" signal "IN5")
		(30 "In14.Cu" signal "GND6")
		(32 "In15.Cu" signal "IN6")
		(34 "In16.Cu" signal "GND7")
		(2 "B.Cu" signal "BOTTOM")
		(9 "F.Adhes" user "F.Adhesive")
		(11 "B.Adhes" user "B.Adhesive")
		(13 "F.Paste" user "Package Geometry/Pastemask Top")
		(15 "B.Paste" user "Package Geometry/Pastemask Bottom")
		(5 "F.SilkS" user "Ref Des/Silkscreen Top")
		(7 "B.SilkS" user "Ref Des/Silkscreen Bottom")
		(1 "F.Mask" user "Board Geometry/Soldermask Top")
		(3 "B.Mask" user "Board Geometry/Soldermask Bottom")
		(17 "Dwgs.User" user "User.Drawings")
		(19 "Cmts.User" user "User.Comments")
		(21 "Eco1.User" user "User.Eco1")
		(23 "Eco2.User" user "User.Eco2")
		(25 "Edge.Cuts" user "Board Geometry/Outline")
		(27 "Margin" user)
		(31 "F.CrtYd" user "Package Geometry/Place Bound Top")
		(29 "B.CrtYd" user "Package Geometry/Place Bound Bottom")
		(35 "F.Fab" user "Ref Des/Assembly Top")
		(33 "B.Fab" user "Ref Des/Assembly Bottom")
	)
	(footprint ""
		(layer "B.Cu")
		(at 194.33413 -351.23882 90)
		(property "Reference" "PC514_2"
			(at 0 0 90)
			(layer "B.SilkS")
			(hide yes)
			(effects
				(font
					(size 1.27 1.27)
				)
				(justify mirror)
			)
		)
		(property "Value" ""
			(at 0 0 90)
			(layer "B.Fab")
			(effects
				(font
					(size 1.27 1.27)
				)
				(justify mirror)
			)
		)
		(duplicate_pad_numbers_are_jumpers no)
		(fp_line
			(start 1.524 -0.762)
			(end -1.524 -0.762)
			(stroke
				(width 0.1524)
				(type default)
			)
			(layer "B.SilkS")
		)
		(fp_line
			(start -1.524 -0.762)
			(end -1.524 0.762)
			(stroke
				(width 0.1524)
				(type default)
			)
			(layer "B.SilkS")
		)
		(fp_line
			(start 1.524 0.762)
			(end 1.524 -0.762)
			(stroke
				(width 0.1524)
				(type default)
			)
			(layer "B.SilkS")
		)
		(fp_line
			(start -1.524 0.762)
			(end 1.524 0.762)
			(stroke
				(width 0.1524)
				(type default)
			)
			(layer "B.SilkS")
		)
		(fp_line
			(start 1.1049 -0.724916)
			(end 1.1049 0.724916)
			(stroke
				(width 0.1)
				(type default)
			)
			(layer "B.Fab")
		)
		(fp_line
			(start -1.1049 -0.724916)
			(end 1.1049 -0.724916)
			(stroke
				(width 0.1)
				(type default)
			)
			(layer "B.Fab")
		)
		(fp_line
			(start 1.1049 0.724916)
			(end -1.1049 0.724916)
			(stroke
				(width 0.1)
				(type default)
			)
			(layer "B.Fab")
		)
		(fp_line
			(start -1.1049 0.724916)
			(end -1.1049 -0.724916)
			(stroke
				(width 0.1)
				(type default)
			)
			(layer "B.Fab")
		)
		(pad "1" smd rect
			(at 0.889 0 90)
			(size 1.016 1.27)
			(layers "B.Cu" "B.Mask" "B.Paste")
			(net "SW_P12V_AUX_PVDD11_S3_P1_FLT")
		)
		(pad "2" smd rect
			(at -0.889 0 90)
			(size 1.016 1.27)
			(layers "B.Cu" "B.Mask" "B.Paste")
			(net "GND")
		)
	)
	(footprint ""
		(layer "B.Cu")
		(at 217.678 -338.582 180)
		(property "Reference" "R6746"
			(at 0 0 0)
			(layer "B.SilkS")
			(hide yes)
			(effects
				(font
					(size 1.27 1.27)
				)
				(justify mirror)
			)
		)
		(property "Value" ""
			(at 0 0 0)
			(layer "B.Fab")
			(effects
				(font
					(size 1.27 1.27)
				)
				(justify mirror)
			)
		)
		(duplicate_pad_numbers_are_jumpers no)
		(fp_line
			(start 0.32512 0.175006)
			(end 0.32512 -0.175006)
			(stroke
				(width 0.1)
				(type default)
			)
			(layer "B.Fab")
		)
		(fp_line
			(start 0.32512 -0.175006)
			(end -0.32512 -0.175006)
			(stroke
				(width 0.1)
				(type default)
			)
			(layer "B.Fab")
		)
		(fp_line
			(start -0.32512 0.175006)
			(end 0.32512 0.175006)
			(stroke
				(width 0.1)
				(type default)
			)
			(layer "B.Fab")
		)
		(fp_line
			(start -0.32512 -0.175006)
			(end -0.32512 0.175006)
			(stroke
				(width 0.1)
				(type default)
			)
			(layer "B.Fab")
		)
		(pad "1" smd rect
			(at 0.2667 0)
			(size 0.3048 0.381)
			(layers "B.Cu" "B.Mask" "B.Paste")
			(net "SMB_RT_CPU1_P3_R_SDA")
		)
		(pad "2" smd rect
			(at -0.2667 0 180)
			(size 0.3048 0.381)
			(layers "B.Cu" "B.Mask" "B.Paste")
			(net "SMB_RT_CPU1_P3_SDA")
		)
	)
	(footprint ""
		(layer "B.Cu")
		(at 231.648 -340.741 -90)
		(property "Reference" "R6763"
			(at 0 0 90)
			(layer "B.SilkS")
			(hide yes)
			(effects
				(font
					(size 1.27 1.27)
				)
				(justify mirror)
			)
		)
		(property "Value" ""
			(at 0 0 90)
			(layer "B.Fab")
			(effects
				(font
					(size 1.27 1.27)
				)
				(justify mirror)
			)
		)
		(duplicate_pad_numbers_are_jumpers no)
		(fp_line
			(start -0.32512 0.175006)
			(end 0.32512 0.175006)
			(stroke
				(width 0.1)
				(type default)
			)
			(layer "B.Fab")
		)
		(fp_line
			(start 0.32512 0.175006)
			(end 0.32512 -0.175006)
			(stroke
				(width 0.1)
				(type default)
			)
			(layer "B.Fab")
		)
		(fp_line
			(start -0.32512 -0.175006)
			(end -0.32512 0.175006)
			(stroke
				(width 0.1)
				(type default)
			)
			(layer "B.Fab")
		)
		(fp_line
			(start 0.32512 -0.175006)
			(end -0.32512 -0.175006)
			(stroke
				(width 0.1)
				(type default)
			)
			(layer "B.Fab")
		)
		(pad "1" smd rect
			(at 0.2667 0 90)
			(size 0.3048 0.381)
			(layers "B.Cu" "B.Mask" "B.Paste")
			(net "P1V8_CPU0_RT_1D")
		)
		(pad "2" smd rect
			(at -0.2667 0 270)
			(size 0.3048 0.381)
			(layers "B.Cu" "B.Mask" "B.Paste")
			(net "SMB_RT_CPU0_P0_R_SCL")
		)
	)
	(footprint ""
		(layer "B.Cu")
		(at 409.018994 -398.942052 90)
		(property "Reference" "C976"
			(at 0 0 90)
			(layer "B.SilkS")
			(hide yes)
			(effects
				(font
					(size 1.27 1.27)
				)
				(justify mirror)
			)
		)
		(property "Value" ""
			(at 0 0 90)
			(layer "B.Fab")
			(effects
				(font
					(size 1.27 1.27)
				)
				(justify mirror)
			)
		)
		(duplicate_pad_numbers_are_jumpers no)
		(fp_line
			(start 0.7874 -0.4064)
			(end -0.7874 -0.4064)
			(stroke
				(width 0.1524)
				(type default)
			)
			(layer "B.SilkS")
		)
		(fp_line
			(start -0.7874 -0.4064)
			(end -0.7874 0.4064)
			(stroke
				(width 0.1524)
				(type default)
			)
			(layer "B.SilkS")
		)
		(fp_line
			(start 0.7874 0.4064)
			(end 0.7874 -0.4064)
			(stroke
				(width 0.1524)
				(type default)
			)
			(layer "B.SilkS")
		)
		(fp_line
			(start -0.7874 0.4064)
			(end 0.7874 0.4064)
			(stroke
				(width 0.1524)
				(type default)
			)
			(layer "B.SilkS")
		)
		(fp_line
			(start 0.67945 -0.305054)
			(end 0.12065 -0.305054)
			(stroke
				(width 0.1)
				(type default)
			)
			(layer "B.Fab")
		)
		(fp_line
			(start 0.12065 -0.305054)
			(end 0.12065 -0.2794)
			(stroke
				(width 0.1)
				(type default)
			)
			(layer "B.Fab")
		)
		(fp_line
			(start -0.12065 -0.3048)
			(end -0.67945 -0.3048)
			(stroke
				(width 0.1)
				(type default)
			)
			(layer "B.Fab")
		)
		(fp_line
			(start -0.67945 -0.3048)
			(end -0.67945 0.3048)
			(stroke
				(width 0.1)
				(type default)
			)
			(layer "B.Fab")
		)
		(fp_line
			(start 0.12065 -0.2794)
			(end -0.12065 -0.2794)
			(stroke
				(width 0.1)
				(type default)
			)
			(layer "B.Fab")
		)
		(fp_line
			(start -0.12065 -0.2794)
			(end -0.12065 -0.3048)
			(stroke
				(width 0.1)
				(type default)
			)
			(layer "B.Fab")
		)
		(fp_line
			(start 0.12065 0.2794)
			(end 0.12065 0.3048)
			(stroke
				(width 0.1)
				(type default)
			)
			(layer "B.Fab")
		)
		(fp_line
			(start -0.120396 0.2794)
			(end 0.12065 0.2794)
			(stroke
				(width 0.1)
				(type default)
			)
			(layer "B.Fab")
		)
		(fp_line
			(start 0.67945 0.3048)
			(end 0.67945 -0.305054)
			(stroke
				(width 0.1)
				(type default)
			)
			(layer "B.Fab")
		)
		(fp_line
			(start 0.12065 0.3048)
			(end 0.67945 0.3048)
			(stroke
				(width 0.1)
				(type default)
			)
			(layer "B.Fab")
		)
		(fp_line
			(start -0.120396 0.3048)
			(end -0.120396 0.2794)
			(stroke
				(width 0.1)
				(type default)
			)
			(layer "B.Fab")
		)
		(fp_line
			(start -0.67945 0.3048)
			(end -0.120396 0.3048)
			(stroke
				(width 0.1)
				(type default)
			)
			(layer "B.Fab")
		)
		(pad "1" smd circle
			(at 0.40005 0 270)
			(size 0 0)
			(layers "B.Cu" "B.Mask" "B.Paste")
			(net "P0V9_CPU0_RT_2D")
		)
		(pad "2" smd circle
			(at -0.40005 0 270)
			(size 0 0)
			(layers "B.Cu" "B.Mask" "B.Paste")
			(net "GND")
		)
	)
)
